(kicad_pcb
	(version 20260206)
	(generator "pcbnew")
	(generator_version "10.0")
	(general
		(thickness 1.6)
		(legacy_teardrops no)
	)
	(paper "A4")
	(title_block
		(title "fcb — Lightning_FCB_BRD.brd")
		(comment 1 "Lightning (Wiwynn / Facebook NVMe JBOF) / footprints 474-481 of 495")
	)
	(layers
		(0 "F.Cu" signal "TOP")
		(4 "In1.Cu" signal "L2GND")
		(6 "In2.Cu" signal "L3VCC")
		(2 "B.Cu" signal "BOTTOM")
		(9 "F.Adhes" user "F.Adhesive")
		(11 "B.Adhes" user "B.Adhesive")
		(13 "F.Paste" user "Package Geometry/Pastemask Top")
		(15 "B.Paste" user "Package Geometry/Pastemask Bottom")
		(5 "F.SilkS" user "Ref Des/Silkscreen Top")
		(7 "B.SilkS" user "Ref Des/Silkscreen Bottom")
		(1 "F.Mask" user "Board Geometry/Soldermask Top")
		(3 "B.Mask" user "Board Geometry/Soldermask Bottom")
		(17 "Dwgs.User" user "User.Drawings")
		(19 "Cmts.User" user "User.Comments")
		(21 "Eco1.User" user "User.Eco1")
		(23 "Eco2.User" user "User.Eco2")
		(25 "Edge.Cuts" user "Board Geometry/Outline")
		(27 "Margin" user)
		(31 "F.CrtYd" user "Package Geometry/Place Bound Top")
		(29 "B.CrtYd" user "Package Geometry/Place Bound Bottom")
		(35 "F.Fab" user "Ref Des/Assembly Top")
		(33 "B.Fab" user "Ref Des/Assembly Bottom")
	)
	(footprint ""
		(layer "F.Cu")
		(at 25.527 -361.188)
		(property "Reference" "PR9"
			(at 0 0 0)
			(layer "F.SilkS")
			(hide yes)
			(effects
				(font
					(size 1.27 1.27)
				)
			)
		)
		(property "Value" "0R2J-2-GP"
			(at 0.064008 -3.993896 0)
			(unlocked yes)
			(layer "F.Fab")
			(hide yes)
			(effects
				(font
					(size 1.016 1.016)
					(thickness 0.1524)
				)
			)
		)
		(property "Device Type" "R402H16"
			(at 0.064008 -5.517896 0)
			(unlocked yes)
			(layer "F.Fab")
			(hide yes)
			(effects
				(font
					(size 1.016 1.016)
					(thickness 0.1524)
				)
			)
		)
		(duplicate_pad_numbers_are_jumpers no)
		(fp_line
			(start -0.508 -0.9398)
			(end -0.508 0.9398)
			(stroke
				(width 0.1524)
				(type default)
			)
			(layer "F.SilkS")
		)
		(fp_line
			(start 0.508 -0.9398)
			(end -0.508 -0.9398)
			(stroke
				(width 0.1524)
				(type default)
			)
			(layer "F.SilkS")
		)
		(fp_rect
			(start -0.508 0.9398)
			(end 0.508 -0.9398)
			(stroke
				(width 0)
				(type default)
			)
			(fill no)
			(layer "F.CrtYd")
		)
		(fp_rect
			(start -0.508 0.9398)
			(end 0.508 -0.9398)
			(stroke
				(width 0)
				(type default)
			)
			(fill no)
			(layer "F.Fab")
		)
		(pad "1" smd custom
			(at 0 -0.4445)
			(size 0.1397 0.1397)
			(layers "F.Cu" "F.Mask" "F.Paste")
			(net "ADM1276_LATCH#")
			(options
				(clearance outline)
				(anchor circle)
			)
			(primitives
				(gr_poly
					(pts
						(arc
							(start -0.1778 -0.2794)
							(mid -0.249642 -0.249642)
							(end -0.2794 -0.1778)
						)
						(arc
							(start -0.2794 0.1778)
							(mid -0.249642 0.249642)
							(end -0.1778 0.2794)
						)
						(arc
							(start 0.1778 0.2794)
							(mid 0.249642 0.249642)
							(end 0.2794 0.1778)
						)
						(arc
							(start 0.2794 -0.1778)
							(mid 0.249642 -0.249642)
							(end 0.1778 -0.2794)
						)
					)
					(width 0)
					(fill yes)
				)
			)
		)
		(pad "2" smd custom
			(at 0 0.4445)
			(size 0.1397 0.1397)
			(layers "F.Cu" "F.Mask" "F.Paste")
			(net "ADM1276_UV")
			(options
				(clearance outline)
				(anchor circle)
			)
			(primitives
				(gr_poly
					(pts
						(arc
							(start -0.1778 -0.2794)
							(mid -0.249642 -0.249642)
							(end -0.2794 -0.1778)
						)
						(arc
							(start -0.2794 0.1778)
							(mid -0.249642 0.249642)
							(end -0.1778 0.2794)
						)
						(arc
							(start 0.1778 0.2794)
							(mid 0.249642 0.249642)
							(end 0.2794 0.1778)
						)
						(arc
							(start 0.2794 -0.1778)
							(mid 0.249642 -0.249642)
							(end 0.1778 -0.2794)
						)
					)
					(width 0)
					(fill yes)
				)
			)
		)
	)
	(footprint ""
		(layer "F.Cu")
		(at 18.237708 -13.905738)
		(property "Reference" "C29"
			(at 0 0 0)
			(layer "F.SilkS")
			(hide yes)
			(effects
				(font
					(size 1.27 1.27)
				)
			)
		)
		(property "Value" "SCD1U16V2KX-3GP"
			(at 1.1811 -2.7051 0)
			(unlocked yes)
			(layer "F.Fab")
			(hide yes)
			(effects
				(font
					(size 1.016 1.016)
					(thickness 0.1524)
				)
			)
		)
		(property "Device Type" "C402H22"
			(at 1.1811 -4.2291 0)
			(unlocked yes)
			(layer "F.Fab")
			(hide yes)
			(effects
				(font
					(size 1.016 1.016)
					(thickness 0.1524)
				)
			)
		)
		(duplicate_pad_numbers_are_jumpers no)
		(fp_rect
			(start -0.4318 0.9525)
			(end 0.4318 -0.9525)
			(stroke
				(width 0)
				(type default)
			)
			(fill no)
			(layer "F.CrtYd")
		)
		(fp_rect
			(start -0.4318 0.9525)
			(end 0.4318 -0.9525)
			(stroke
				(width 0)
				(type default)
			)
			(fill no)
			(layer "F.Fab")
		)
		(pad "1" smd custom
			(at 0 -0.4445)
			(size 0.1524 0.1524)
			(layers "F.Cu" "F.Mask" "F.Paste")
			(net "FAN_TACH11")
			(options
				(clearance outline)
				(anchor circle)
			)
			(primitives
				(gr_poly
					(pts
						(arc
							(start 0.3048 -0.2032)
							(mid 0.275042 -0.275042)
							(end 0.2032 -0.3048)
						)
						(arc
							(start -0.2032 -0.3048)
							(mid -0.275042 -0.275042)
							(end -0.3048 -0.2032)
						)
						(arc
							(start -0.3048 0.2032)
							(mid -0.275042 0.275042)
							(end -0.2032 0.3048)
						)
						(arc
							(start 0.2032 0.3048)
							(mid 0.275042 0.275042)
							(end 0.3048 0.2032)
						)
					)
					(width 0)
					(fill yes)
				)
			)
		)
		(pad "2" smd custom
			(at 0 0.4445)
			(size 0.1524 0.1524)
			(layers "F.Cu" "F.Mask" "F.Paste")
			(net "GND")
			(options
				(clearance outline)
				(anchor circle)
			)
			(primitives
				(gr_poly
					(pts
						(arc
							(start 0.3048 -0.2032)
							(mid 0.275042 -0.275042)
							(end 0.2032 -0.3048)
						)
						(arc
							(start -0.2032 -0.3048)
							(mid -0.275042 -0.275042)
							(end -0.3048 -0.2032)
						)
						(arc
							(start -0.3048 0.2032)
							(mid -0.275042 0.275042)
							(end -0.2032 0.3048)
						)
						(arc
							(start 0.2032 0.3048)
							(mid 0.275042 0.275042)
							(end 0.3048 0.2032)
						)
					)
					(width 0)
					(fill yes)
				)
			)
		)
	)
	(footprint ""
		(layer "F.Cu")
		(at 17.63649 -172.175424 180)
		(property "Reference" "U3"
			(at 0 0 180)
			(layer "F.SilkS")
			(hide yes)
			(effects
				(font
					(size 1.27 1.27)
				)
			)
		)
		(property "Value" "74LVC1G32GW-1GP"
			(at -2.3368 -8.6868 180)
			(unlocked yes)
			(layer "F.Fab")
			(hide yes)
			(effects
				(font
					(size 1.016 1.016)
					(thickness 0.1524)
				)
			)
		)
		(property "Device Type" "SC70-5H44"
			(at -2.3114 -10.414 180)
			(unlocked yes)
			(layer "F.Fab")
			(hide yes)
			(effects
				(font
					(size 1.016 1.016)
					(thickness 0.1524)
				)
			)
		)
		(duplicate_pad_numbers_are_jumpers no)
		(fp_line
			(start 1.3843 -1.8034)
			(end 1.3843 -1.1176)
			(stroke
				(width 0.3302)
				(type default)
			)
			(layer "F.SilkS")
		)
		(fp_line
			(start 1.27 1.7018)
			(end -1.27 1.7018)
			(stroke
				(width 0.1524)
				(type default)
			)
			(layer "F.SilkS")
		)
		(fp_line
			(start 1.27 -1.7018)
			(end 1.27 1.7018)
			(stroke
				(width 0.1524)
				(type default)
			)
			(layer "F.SilkS")
		)
		(fp_line
			(start 0.6604 -1.8034)
			(end 1.3843 -1.8034)
			(stroke
				(width 0.3302)
				(type default)
			)
			(layer "F.SilkS")
		)
		(fp_line
			(start -1.27 1.7018)
			(end -1.27 -1.7018)
			(stroke
				(width 0.1524)
				(type default)
			)
			(layer "F.SilkS")
		)
		(fp_line
			(start -1.27 -1.7018)
			(end 1.27 -1.7018)
			(stroke
				(width 0.1524)
				(type default)
			)
			(layer "F.SilkS")
		)
		(fp_rect
			(start -1.524 1.9558)
			(end 1.524 -1.9558)
			(stroke
				(width 0)
				(type default)
			)
			(fill no)
			(layer "F.CrtYd")
		)
		(fp_poly
			(pts
				(xy -1.524 -1.9558) (xy 1.524 -1.9558) (xy 1.524 1.9558) (xy -1.524 1.9558)
			)
			(stroke
				(width 0)
				(type default)
			)
			(fill no)
			(layer "F.Fab")
		)
		(pad "1" smd rect
			(at 0.65024 -0.8255 180)
			(size 0.4064 1.2192)
			(layers "F.Cu" "F.Mask" "F.Paste")
			(net "SEB_PEER_1A_1B_HB_OUT")
		)
		(pad "2" smd rect
			(at 0 -0.8255 180)
			(size 0.4064 1.2192)
			(layers "F.Cu" "F.Mask" "F.Paste")
			(net "SEB_PEER_2A_2B_HB_OUT")
		)
		(pad "3" smd rect
			(at -0.65024 -0.8255 180)
			(size 0.4064 1.2192)
			(layers "F.Cu" "F.Mask" "F.Paste")
			(net "GND")
		)
		(pad "4" smd rect
			(at -0.65024 0.8255 180)
			(size 0.4064 1.2192)
			(layers "F.Cu" "F.Mask" "F.Paste")
			(net "THERMHOT#_R")
		)
		(pad "5" smd rect
			(at 0.65024 0.8255 180)
			(size 0.4064 1.2192)
			(layers "F.Cu" "F.Mask" "F.Paste")
			(net "P3V3")
		)
	)
	(footprint ""
		(layer "F.Cu")
		(at 31.242 -361.315 180)
		(property "Reference" "R109"
			(at 0 0 180)
			(layer "F.SilkS")
			(hide yes)
			(effects
				(font
					(size 1.27 1.27)
				)
			)
		)
		(property "Value" "0R2J-2-GP"
			(at 0.064008 -3.993896 180)
			(unlocked yes)
			(layer "F.Fab")
			(hide yes)
			(effects
				(font
					(size 1.016 1.016)
					(thickness 0.1524)
				)
			)
		)
		(property "Device Type" "R402H16"
			(at 0.064008 -5.517896 180)
			(unlocked yes)
			(layer "F.Fab")
			(hide yes)
			(effects
				(font
					(size 1.016 1.016)
					(thickness 0.1524)
				)
			)
		)
		(duplicate_pad_numbers_are_jumpers no)
		(fp_line
			(start 0.508 -0.9398)
			(end -0.508 -0.9398)
			(stroke
				(width 0.1524)
				(type default)
			)
			(layer "F.SilkS")
		)
		(fp_line
			(start -0.508 -0.9398)
			(end -0.508 0.9398)
			(stroke
				(width 0.1524)
				(type default)
			)
			(layer "F.SilkS")
		)
		(fp_rect
			(start -0.508 0.9398)
			(end 0.508 -0.9398)
			(stroke
				(width 0)
				(type default)
			)
			(fill no)
			(layer "F.CrtYd")
		)
		(fp_rect
			(start -0.508 0.9398)
			(end 0.508 -0.9398)
			(stroke
				(width 0)
				(type default)
			)
			(fill no)
			(layer "F.Fab")
		)
		(pad "1" smd custom
			(at 0 -0.4445 180)
			(size 0.1397 0.1397)
			(layers "F.Cu" "F.Mask" "F.Paste")
			(net "I2C_C_SDA")
			(options
				(clearance outline)
				(anchor circle)
			)
			(primitives
				(gr_poly
					(pts
						(arc
							(start -0.1778 -0.2794)
							(mid -0.249642 -0.249642)
							(end -0.2794 -0.1778)
						)
						(arc
							(start -0.2794 0.1778)
							(mid -0.249642 0.249642)
							(end -0.1778 0.2794)
						)
						(arc
							(start 0.1778 0.2794)
							(mid 0.249642 0.249642)
							(end 0.2794 0.1778)
						)
						(arc
							(start 0.2794 -0.1778)
							(mid 0.249642 -0.249642)
							(end 0.1778 -0.2794)
						)
					)
					(width 0)
					(fill yes)
				)
			)
		)
		(pad "2" smd custom
			(at 0 0.4445 180)
			(size 0.1397 0.1397)
			(layers "F.Cu" "F.Mask" "F.Paste")
			(net "I2C_C_SDA_ADM1276")
			(options
				(clearance outline)
				(anchor circle)
			)
			(primitives
				(gr_poly
					(pts
						(arc
							(start -0.1778 -0.2794)
							(mid -0.249642 -0.249642)
							(end -0.2794 -0.1778)
						)
						(arc
							(start -0.2794 0.1778)
							(mid -0.249642 0.249642)
							(end -0.1778 0.2794)
						)
						(arc
							(start 0.1778 0.2794)
							(mid 0.249642 0.249642)
							(end 0.2794 0.1778)
						)
						(arc
							(start 0.2794 -0.1778)
							(mid 0.249642 -0.249642)
							(end 0.1778 -0.2794)
						)
					)
					(width 0)
					(fill yes)
				)
			)
		)
	)
	(footprint ""
		(layer "F.Cu")
		(at 36.740338 -477.189292 90)
		(property "Reference" "C50"
			(at 0 0 90)
			(layer "F.SilkS")
			(hide yes)
			(effects
				(font
					(size 1.27 1.27)
				)
			)
		)
		(property "Value" "SC1U25V3KX-1-GP"
			(at 0 -2.8194 90)
			(unlocked yes)
			(layer "F.Fab")
			(hide yes)
			(effects
				(font
					(size 1.016 1.016)
					(thickness 0.1524)
				)
			)
		)
		(property "Device Type" "C603H36"
			(at 0 -4.3434 90)
			(unlocked yes)
			(layer "F.Fab")
			(hide yes)
			(effects
				(font
					(size 1.016 1.016)
					(thickness 0.1524)
				)
			)
		)
		(duplicate_pad_numbers_are_jumpers no)
		(fp_line
			(start 0.508 0)
			(end -0.508 0)
			(stroke
				(width 0.2032)
				(type default)
			)
			(layer "F.SilkS")
		)
		(fp_rect
			(start -0.5842 1.3335)
			(end 0.5842 -1.3335)
			(stroke
				(width 0)
				(type default)
			)
			(fill no)
			(layer "F.CrtYd")
		)
		(fp_rect
			(start -0.5842 1.3335)
			(end 0.5842 -1.3335)
			(stroke
				(width 0)
				(type default)
			)
			(fill no)
			(layer "F.Fab")
		)
		(pad "1" smd custom
			(at 0 -0.762 90)
			(size 0.2159 0.2159)
			(layers "F.Cu" "F.Mask" "F.Paste")
			(net "P12V")
			(options
				(clearance outline)
				(anchor circle)
			)
			(primitives
				(gr_poly
					(pts
						(arc
							(start -0.3302 -0.4318)
							(mid -0.402042 -0.402042)
							(end -0.4318 -0.3302)
						)
						(arc
							(start -0.4318 0.3302)
							(mid -0.402042 0.402042)
							(end -0.3302 0.4318)
						)
						(arc
							(start 0.3302 0.4318)
							(mid 0.402042 0.402042)
							(end 0.4318 0.3302)
						)
						(arc
							(start 0.4318 -0.3302)
							(mid 0.402042 -0.402042)
							(end 0.3302 -0.4318)
						)
					)
					(width 0)
					(fill yes)
				)
			)
		)
		(pad "2" smd custom
			(at 0 0.762 90)
			(size 0.2159 0.2159)
			(layers "F.Cu" "F.Mask" "F.Paste")
			(net "GND")
			(options
				(clearance outline)
				(anchor circle)
			)
			(primitives
				(gr_poly
					(pts
						(arc
							(start -0.3302 -0.4318)
							(mid -0.402042 -0.402042)
							(end -0.4318 -0.3302)
						)
						(arc
							(start -0.4318 0.3302)
							(mid -0.402042 0.402042)
							(end -0.3302 0.4318)
						)
						(arc
							(start 0.3302 0.4318)
							(mid 0.402042 0.402042)
							(end 0.4318 0.3302)
						)
						(arc
							(start 0.4318 -0.3302)
							(mid 0.402042 -0.402042)
							(end 0.3302 -0.4318)
						)
					)
					(width 0)
					(fill yes)
				)
			)
		)
	)
	(footprint ""
		(layer "F.Cu")
		(at 20.7264 -26.162 90)
		(property "Reference" "R182"
			(at 0 0 90)
			(layer "F.SilkS")
			(hide yes)
			(effects
				(font
					(size 1.27 1.27)
				)
			)
		)
		(property "Value" "0R1206-PAD-1-GP"
			(at 0 -5.0292 90)
			(unlocked yes)
			(layer "F.Fab")
			(hide yes)
			(effects
				(font
					(size 1.016 1.016)
					(thickness 0.1524)
				)
			)
		)
		(property "Device Type" "0R1206-PAD-1"
			(at 0 -6.5532 90)
			(unlocked yes)
			(layer "F.Fab")
			(hide yes)
			(effects
				(font
					(size 1.016 1.016)
					(thickness 0.1524)
				)
			)
		)
		(duplicate_pad_numbers_are_jumpers no)
		(fp_line
			(start 1.016 -2.2352)
			(end -1.016 -2.2352)
			(stroke
				(width 0.1524)
				(type default)
			)
			(layer "F.SilkS")
		)
		(fp_line
			(start -1.016 -2.2352)
			(end -1.016 2.2352)
			(stroke
				(width 0.1524)
				(type default)
			)
			(layer "F.SilkS")
		)
		(fp_line
			(start 1.016 2.2352)
			(end 1.016 -2.2352)
			(stroke
				(width 0.1524)
				(type default)
			)
			(layer "F.SilkS")
		)
		(fp_line
			(start -1.016 2.2352)
			(end 1.016 2.2352)
			(stroke
				(width 0.1524)
				(type default)
			)
			(layer "F.SilkS")
		)
		(fp_rect
			(start -1.0922 2.3114)
			(end 1.0922 -2.3114)
			(stroke
				(width 0)
				(type default)
			)
			(fill no)
			(layer "F.CrtYd")
		)
		(fp_poly
			(pts
				(xy -1.0922 -2.3114) (xy 1.0922 -2.3114) (xy 1.0922 2.3114) (xy -1.0922 2.3114)
			)
			(stroke
				(width 0)
				(type default)
			)
			(fill no)
			(layer "F.Fab")
		)
		(pad "1" smd rect
			(at 0 -1.397 90)
			(size 1.651 2.0574)
			(drill
				(offset 0 0.3937)
			)
			(layers "F.Cu" "F.Mask" "F.Paste")
			(net "P12V_FAN6")
		)
		(pad "2" smd rect
			(at 0 1.397 90)
			(size 1.651 2.0574)
			(drill
				(offset 0 -0.3937)
			)
			(layers "F.Cu" "F.Mask" "F.Paste")
			(net "P12V")
		)
	)
	(footprint ""
		(layer "F.Cu")
		(at 16.4592 -260.35 -90)
		(property "Reference" "R84"
			(at 0 0 270)
			(layer "F.SilkS")
			(hide yes)
			(effects
				(font
					(size 1.27 1.27)
				)
			)
		)
		(property "Value" "27KR3F-GP"
			(at -0.0254 -2.5146 270)
			(unlocked yes)
			(layer "F.Fab")
			(hide yes)
			(effects
				(font
					(size 1.016 1.016)
					(thickness 0.1524)
				)
			)
		)
		(property "Device Type" "R603H22"
			(at -0.0254 -4.0386 270)
			(unlocked yes)
			(layer "F.Fab")
			(hide yes)
			(effects
				(font
					(size 1.016 1.016)
					(thickness 0.1524)
				)
			)
		)
		(duplicate_pad_numbers_are_jumpers no)
		(fp_line
			(start -0.4826 0)
			(end -0.2032 0)
			(stroke
				(width 0.2032)
				(type default)
			)
			(layer "F.SilkS")
		)
		(fp_line
			(start 0.2032 0)
			(end 0.4826 0)
			(stroke
				(width 0.2032)
				(type default)
			)
			(layer "F.SilkS")
		)
		(fp_rect
			(start -0.5842 1.3335)
			(end 0.5842 -1.3335)
			(stroke
				(width 0)
				(type default)
			)
			(fill no)
			(layer "F.CrtYd")
		)
		(fp_rect
			(start -0.5842 1.3335)
			(end 0.5842 -1.3335)
			(stroke
				(width 0)
				(type default)
			)
			(fill no)
			(layer "F.Fab")
		)
		(pad "1" smd custom
			(at 0 -0.762 270)
			(size 0.2159 0.2159)
			(layers "F.Cu" "F.Mask" "F.Paste")
			(net "FAN_TACH6")
			(options
				(clearance outline)
				(anchor circle)
			)
			(primitives
				(gr_poly
					(pts
						(arc
							(start -0.3302 -0.4318)
							(mid -0.402042 -0.402042)
							(end -0.4318 -0.3302)
						)
						(arc
							(start -0.4318 0.3302)
							(mid -0.402042 0.402042)
							(end -0.3302 0.4318)
						)
						(arc
							(start 0.3302 0.4318)
							(mid 0.402042 0.402042)
							(end 0.4318 0.3302)
						)
						(arc
							(start 0.4318 -0.3302)
							(mid 0.402042 -0.402042)
							(end 0.3302 -0.4318)
						)
					)
					(width 0)
					(fill yes)
				)
			)
		)
		(pad "2" smd custom
			(at 0 0.762 270)
			(size 0.2159 0.2159)
			(layers "F.Cu" "F.Mask" "F.Paste")
			(net "FANIN_6")
			(options
				(clearance outline)
				(anchor circle)
			)
			(primitives
				(gr_poly
					(pts
						(arc
							(start -0.3302 -0.4318)
							(mid -0.402042 -0.402042)
							(end -0.4318 -0.3302)
						)
						(arc
							(start -0.4318 0.3302)
							(mid -0.402042 0.402042)
							(end -0.3302 0.4318)
						)
						(arc
							(start 0.3302 0.4318)
							(mid 0.402042 0.402042)
							(end 0.4318 0.3302)
						)
						(arc
							(start 0.4318 -0.3302)
							(mid 0.402042 -0.402042)
							(end 0.3302 -0.4318)
						)
					)
					(width 0)
					(fill yes)
				)
			)
		)
	)
	(footprint ""
		(layer "F.Cu")
		(at 23.614634 -156.80309 -90)
		(property "Reference" "TP16"
			(at 0 0 270)
			(layer "F.SilkS")
			(hide yes)
			(effects
				(font
					(size 1.27 1.27)
				)
			)
		)
		(property "Value" "TPAD32-GP"
			(at 0 -3.166364 270)
			(unlocked yes)
			(layer "F.Fab")
			(hide yes)
			(effects
				(font
					(size 1.016 1.016)
					(thickness 0.1524)
				)
			)
		)
		(property "Device Type" "TPAD32"
			(at 0 -4.690618 270)
			(unlocked yes)
			(layer "F.Fab")
			(hide yes)
			(effects
				(font
					(size 1.016 1.016)
					(thickness 0.1524)
				)
			)
		)
		(duplicate_pad_numbers_are_jumpers no)
		(fp_poly
			(pts
				(arc
					(start 0.7112 0)
					(mid -0.7112 0)
					(end 0.7112 0)
				)
			)
			(stroke
				(width 0)
				(type default)
			)
			(fill no)
			(layer "F.CrtYd")
		)
		(fp_poly
			(pts
				(arc
					(start 0.7112 0)
					(mid -0.7112 0)
					(end 0.7112 0)
				)
			)
			(stroke
				(width 0)
				(type default)
			)
			(fill no)
			(layer "F.Fab")
		)
		(pad "1" smd circle
			(at 0 0 270)
			(size 0.8128 0.8128)
			(layers "F.Cu" "F.Mask" "F.Paste")
			(net "NCT7904_LED")
		)
	)
)
